(kicad_pcb
	(version 20260206)
	(generator "pcbnew")
	(generator_version "10.0")
	(general
		(thickness 1.6)
		(legacy_teardrops no)
	)
	(paper "A4")
	(title_block
		(title "Bryce Canyon_R.DPB_16317-1_OCP.brd")
		(comment 1 "Bryce Canyon / footprints 1106-1112 of 2099")
	)
	(layers
		(0 "F.Cu" signal "TOP")
		(4 "In1.Cu" signal "L2GND")
		(6 "In2.Cu" signal "L3")
		(8 "In3.Cu" signal "L4VCC")
		(10 "In4.Cu" signal "L5VCC")
		(12 "In5.Cu" signal "L6")
		(14 "In6.Cu" signal "L7GND")
		(2 "B.Cu" signal "BOTTOM")
		(9 "F.Adhes" user "F.Adhesive")
		(11 "B.Adhes" user "B.Adhesive")
		(13 "F.Paste" user "Package Geometry/Pastemask Top")
		(15 "B.Paste" user "Package Geometry/Pastemask Bottom")
		(5 "F.SilkS" user "Ref Des/Silkscreen Top")
		(7 "B.SilkS" user "Ref Des/Silkscreen Bottom")
		(1 "F.Mask" user "Board Geometry/Soldermask Top")
		(3 "B.Mask" user "Board Geometry/Soldermask Bottom")
		(17 "Dwgs.User" user "User.Drawings")
		(19 "Cmts.User" user "User.Comments")
		(21 "Eco1.User" user "User.Eco1")
		(23 "Eco2.User" user "User.Eco2")
		(25 "Edge.Cuts" user "Board Geometry/Outline")
		(27 "Margin" user)
		(31 "F.CrtYd" user "Package Geometry/Place Bound Top")
		(29 "B.CrtYd" user "Package Geometry/Place Bound Bottom")
		(35 "F.Fab" user "Ref Des/Assembly Top")
		(33 "B.Fab" user "Ref Des/Assembly Bottom")
	)
	(footprint ""
		(layer "F.Cu")
		(at 256.499614 -227.34143 90)
		(property "Reference" "C39"
			(at 0 0 90)
			(layer "F.SilkS")
			(hide yes)
			(effects
				(font
					(size 1.27 1.27)
				)
			)
		)
		(property "Value" "SCD1U16V2KX-3GP"
			(at 1.1811 -2.7051 90)
			(unlocked yes)
			(layer "F.Fab")
			(hide yes)
			(effects
				(font
					(size 1.016 1.016)
					(thickness 0.1524)
				)
			)
		)
		(property "Device Type" "C402H22"
			(at 1.1811 -4.2291 90)
			(unlocked yes)
			(layer "F.Fab")
			(hide yes)
			(effects
				(font
					(size 1.016 1.016)
					(thickness 0.1524)
				)
			)
		)
		(duplicate_pad_numbers_are_jumpers no)
		(fp_rect
			(start -0.4318 0.9525)
			(end 0.4318 -0.9525)
			(stroke
				(width 0)
				(type default)
			)
			(fill no)
			(layer "F.CrtYd")
		)
		(fp_rect
			(start -0.4318 0.9525)
			(end 0.4318 -0.9525)
			(stroke
				(width 0)
				(type default)
			)
			(fill no)
			(layer "F.Fab")
		)
		(pad "1" smd custom
			(at 0 -0.4445 90)
			(size 0.1524 0.1524)
			(layers "F.Cu" "F.Mask" "F.Paste")
			(net "P5V_B_2_SENSE")
			(options
				(clearance outline)
				(anchor circle)
			)
			(primitives
				(gr_poly
					(pts
						(arc
							(start 0.3048 -0.2032)
							(mid 0.275042 -0.275042)
							(end 0.2032 -0.3048)
						)
						(arc
							(start -0.2032 -0.3048)
							(mid -0.275042 -0.275042)
							(end -0.3048 -0.2032)
						)
						(arc
							(start -0.3048 0.2032)
							(mid -0.275042 0.275042)
							(end -0.2032 0.3048)
						)
						(arc
							(start 0.2032 0.3048)
							(mid 0.275042 0.275042)
							(end 0.3048 0.2032)
						)
					)
					(width 0)
					(fill yes)
				)
			)
		)
		(pad "2" smd custom
			(at 0 0.4445 90)
			(size 0.1524 0.1524)
			(layers "F.Cu" "F.Mask" "F.Paste")
			(net "GND")
			(options
				(clearance outline)
				(anchor circle)
			)
			(primitives
				(gr_poly
					(pts
						(arc
							(start 0.3048 -0.2032)
							(mid 0.275042 -0.275042)
							(end 0.2032 -0.3048)
						)
						(arc
							(start -0.2032 -0.3048)
							(mid -0.275042 -0.275042)
							(end -0.3048 -0.2032)
						)
						(arc
							(start -0.3048 0.2032)
							(mid -0.275042 0.275042)
							(end -0.2032 0.3048)
						)
						(arc
							(start 0.2032 0.3048)
							(mid 0.275042 0.275042)
							(end 0.3048 0.2032)
						)
					)
					(width 0)
					(fill yes)
				)
			)
		)
	)
	(footprint ""
		(layer "F.Cu")
		(at 52.197 -26.289 180)
		(property "Reference" "Q124"
			(at 0 0 180)
			(layer "F.SilkS")
			(hide yes)
			(effects
				(font
					(size 1.27 1.27)
				)
			)
		)
		(property "Value" "AO4406AL-GP"
			(at -3.707384 -1.5367 180)
			(unlocked yes)
			(layer "F.Fab")
			(hide yes)
			(effects
				(font
					(size 1.016 1.016)
					(thickness 0.1524)
				)
			)
		)
		(property "Device Type" "SOIC8H69"
			(at -3.707384 -3.0607 180)
			(unlocked yes)
			(layer "F.Fab")
			(hide yes)
			(effects
				(font
					(size 1.016 1.016)
					(thickness 0.1524)
				)
			)
		)
		(duplicate_pad_numbers_are_jumpers no)
		(fp_line
			(start 2.1336 1.4224)
			(end 2.1336 -1.4224)
			(stroke
				(width 0.1524)
				(type default)
			)
			(layer "F.SilkS")
		)
		(fp_line
			(start 2.1336 -1.4224)
			(end -2.7432 -1.4224)
			(stroke
				(width 0.1524)
				(type default)
			)
			(layer "F.SilkS")
		)
		(fp_line
			(start -2.1844 -0.0508)
			(end -2.7178 0.508)
			(stroke
				(width 0.1524)
				(type default)
			)
			(layer "F.SilkS")
		)
		(fp_line
			(start -2.6289 3.4417)
			(end -2.6289 1.4732)
			(stroke
				(width 0.381)
				(type default)
			)
			(layer "F.SilkS")
		)
		(fp_line
			(start -2.7178 -0.508)
			(end -2.1844 -0.0508)
			(stroke
				(width 0.1524)
				(type default)
			)
			(layer "F.SilkS")
		)
		(fp_line
			(start -2.7432 1.4224)
			(end 2.1336 1.4224)
			(stroke
				(width 0.1524)
				(type default)
			)
			(layer "F.SilkS")
		)
		(fp_line
			(start -2.7432 1.4224)
			(end -2.6416 1.4224)
			(stroke
				(width 0.1524)
				(type default)
			)
			(layer "F.SilkS")
		)
		(fp_line
			(start -2.7432 -1.4224)
			(end -2.7432 1.4224)
			(stroke
				(width 0.1524)
				(type default)
			)
			(layer "F.SilkS")
		)
		(fp_poly
			(pts
				(xy -2.2098 -1.4224) (xy -2.2098 1.4224) (xy 2.2098 1.4224) (xy 2.2098 -1.4224)
			)
			(stroke
				(width 0)
				(type default)
			)
			(fill yes)
			(layer "F.SilkS")
		)
		(fp_rect
			(start -2.450084 2.999994)
			(end 2.450084 -2.999994)
			(stroke
				(width 0)
				(type default)
			)
			(fill no)
			(layer "F.CrtYd")
		)
		(fp_poly
			(pts
				(xy -2.8194 3.6322) (xy -2.8194 -3.6322) (xy 2.8194 -3.6322) (xy 2.8194 1.18364) (xy 2.450084 1.18364)
				(xy 2.450084 -2.999994) (xy -2.450084 -2.999994) (xy -2.450084 2.999994) (xy 2.450084 2.999994)
				(xy 2.450084 1.18618) (xy 2.8194 1.18618) (xy 2.8194 3.6322)
			)
			(stroke
				(width 0)
				(type default)
			)
			(fill no)
			(layer "F.CrtYd")
		)
		(fp_rect
			(start -2.8194 3.6322)
			(end 2.8194 -3.6322)
			(stroke
				(width 0)
				(type default)
			)
			(fill no)
			(layer "F.Fab")
		)
		(pad "1" smd rect
			(at -1.905 2.54 180)
			(size 0.635 1.651)
			(layers "F.Cu" "F.Mask" "F.Paste")
			(net "P5V_HDD25")
		)
		(pad "2" smd rect
			(at -0.635 2.54 180)
			(size 0.635 1.651)
			(layers "F.Cu" "F.Mask" "F.Paste")
			(net "P5V_HDD25")
		)
		(pad "3" smd rect
			(at 0.635 2.54 180)
			(size 0.635 1.651)
			(layers "F.Cu" "F.Mask" "F.Paste")
			(net "P5V_HDD25")
		)
		(pad "4" smd rect
			(at 1.905 2.54 180)
			(size 0.635 1.651)
			(layers "F.Cu" "F.Mask" "F.Paste")
			(net "SW_HDD_P25")
		)
		(pad "5" smd rect
			(at 1.905 -2.54 180)
			(size 0.635 1.651)
			(layers "F.Cu" "F.Mask" "F.Paste")
			(net "P5V_B_2")
		)
		(pad "6" smd rect
			(at 0.635 -2.54 180)
			(size 0.635 1.651)
			(layers "F.Cu" "F.Mask" "F.Paste")
			(net "P5V_B_2")
		)
		(pad "7" smd rect
			(at -0.635 -2.54 180)
			(size 0.635 1.651)
			(layers "F.Cu" "F.Mask" "F.Paste")
			(net "P5V_B_2")
		)
		(pad "8" smd rect
			(at -1.905 -2.54 180)
			(size 0.635 1.651)
			(layers "F.Cu" "F.Mask" "F.Paste")
			(net "P5V_B_2")
		)
	)
	(footprint ""
		(layer "F.Cu")
		(at 35.306 -148.082 -90)
		(property "Reference" "R351"
			(at 0 0 270)
			(layer "F.SilkS")
			(hide yes)
			(effects
				(font
					(size 1.27 1.27)
				)
			)
		)
		(property "Value" "10KR2F-2-GP"
			(at 0.064008 -3.993896 270)
			(unlocked yes)
			(layer "F.Fab")
			(hide yes)
			(effects
				(font
					(size 1.016 1.016)
					(thickness 0.1524)
				)
			)
		)
		(property "Device Type" "R402H16"
			(at 0.064008 -5.517896 270)
			(unlocked yes)
			(layer "F.Fab")
			(hide yes)
			(effects
				(font
					(size 1.016 1.016)
					(thickness 0.1524)
				)
			)
		)
		(duplicate_pad_numbers_are_jumpers no)
		(fp_line
			(start -0.508 -0.9398)
			(end -0.508 0.9398)
			(stroke
				(width 0.1524)
				(type default)
			)
			(layer "F.SilkS")
		)
		(fp_line
			(start 0.508 -0.9398)
			(end -0.508 -0.9398)
			(stroke
				(width 0.1524)
				(type default)
			)
			(layer "F.SilkS")
		)
		(fp_rect
			(start -0.508 0.9398)
			(end 0.508 -0.9398)
			(stroke
				(width 0)
				(type default)
			)
			(fill no)
			(layer "F.CrtYd")
		)
		(fp_rect
			(start -0.508 0.9398)
			(end 0.508 -0.9398)
			(stroke
				(width 0)
				(type default)
			)
			(fill no)
			(layer "F.Fab")
		)
		(pad "1" smd custom
			(at 0 -0.4445 270)
			(size 0.1397 0.1397)
			(layers "F.Cu" "F.Mask" "F.Paste")
			(net "P3V3_STBY_B")
			(options
				(clearance outline)
				(anchor circle)
			)
			(primitives
				(gr_poly
					(pts
						(arc
							(start -0.1778 -0.2794)
							(mid -0.249642 -0.249642)
							(end -0.2794 -0.1778)
						)
						(arc
							(start -0.2794 0.1778)
							(mid -0.249642 0.249642)
							(end -0.1778 0.2794)
						)
						(arc
							(start 0.1778 0.2794)
							(mid 0.249642 0.249642)
							(end 0.2794 0.1778)
						)
						(arc
							(start 0.2794 -0.1778)
							(mid 0.249642 -0.249642)
							(end 0.1778 -0.2794)
						)
					)
					(width 0)
					(fill yes)
				)
			)
		)
		(pad "2" smd custom
			(at 0 0.4445 270)
			(size 0.1397 0.1397)
			(layers "F.Cu" "F.Mask" "F.Paste")
			(net "HDD_PRSNT_12")
			(options
				(clearance outline)
				(anchor circle)
			)
			(primitives
				(gr_poly
					(pts
						(arc
							(start -0.1778 -0.2794)
							(mid -0.249642 -0.249642)
							(end -0.2794 -0.1778)
						)
						(arc
							(start -0.2794 0.1778)
							(mid -0.249642 0.249642)
							(end -0.1778 0.2794)
						)
						(arc
							(start 0.1778 0.2794)
							(mid 0.249642 0.249642)
							(end 0.2794 0.1778)
						)
						(arc
							(start 0.2794 -0.1778)
							(mid 0.249642 -0.249642)
							(end 0.1778 -0.2794)
						)
					)
					(width 0)
					(fill yes)
				)
			)
		)
	)
	(footprint ""
		(layer "F.Cu")
		(at 331.47 -32.004 -90)
		(property "Reference" "R759"
			(at 0 0 270)
			(layer "F.SilkS")
			(hide yes)
			(effects
				(font
					(size 1.27 1.27)
				)
			)
		)
		(property "Value" "2R6F-GP"
			(at -0.0508 -4.8514 270)
			(unlocked yes)
			(layer "F.Fab")
			(hide yes)
			(effects
				(font
					(size 1.016 1.016)
					(thickness 0.1524)
				)
			)
		)
		(property "Device Type" "R1206H26"
			(at 0 -6.3754 270)
			(unlocked yes)
			(layer "F.Fab")
			(hide yes)
			(effects
				(font
					(size 1.016 1.016)
					(thickness 0.1524)
				)
			)
		)
		(duplicate_pad_numbers_are_jumpers no)
		(fp_line
			(start -1.016 2.2352)
			(end -1.016 -2.2352)
			(stroke
				(width 0.1524)
				(type default)
			)
			(layer "F.SilkS")
		)
		(fp_line
			(start 1.016 2.2352)
			(end -1.016 2.2352)
			(stroke
				(width 0.1524)
				(type default)
			)
			(layer "F.SilkS")
		)
		(fp_line
			(start -1.016 -2.2352)
			(end 1.016 -2.2352)
			(stroke
				(width 0.1524)
				(type default)
			)
			(layer "F.SilkS")
		)
		(fp_line
			(start 1.016 -2.2352)
			(end 1.016 2.2352)
			(stroke
				(width 0.1524)
				(type default)
			)
			(layer "F.SilkS")
		)
		(fp_rect
			(start -1.0922 2.3114)
			(end 1.0922 -2.3114)
			(stroke
				(width 0)
				(type default)
			)
			(fill no)
			(layer "F.CrtYd")
		)
		(fp_poly
			(pts
				(xy -1.0922 -2.3114) (xy 1.0922 -2.3114) (xy 1.0922 2.3114) (xy -1.0922 2.3114)
			)
			(stroke
				(width 0)
				(type default)
			)
			(fill no)
			(layer "F.Fab")
		)
		(pad "1" smd rect
			(at 0 -1.397 270)
			(size 1.651 1.27)
			(layers "F.Cu" "F.Mask" "F.Paste")
			(net "P5V_HDD30")
		)
		(pad "2" smd rect
			(at 0 1.397 270)
			(size 1.651 1.27)
			(layers "F.Cu" "F.Mask" "F.Paste")
			(net "5V_PRE_30")
		)
	)
	(footprint ""
		(layer "F.Cu")
		(at 24.196802 -224.31375)
		(property "Reference" "R1101"
			(at 0 0 0)
			(layer "F.SilkS")
			(hide yes)
			(effects
				(font
					(size 1.27 1.27)
				)
			)
		)
		(property "Value" "0R3J-0-U-GP"
			(at -0.0254 -2.5146 0)
			(unlocked yes)
			(layer "F.Fab")
			(hide yes)
			(effects
				(font
					(size 1.016 1.016)
					(thickness 0.1524)
				)
			)
		)
		(property "Device Type" "R603H22"
			(at -0.0254 -4.0386 0)
			(unlocked yes)
			(layer "F.Fab")
			(hide yes)
			(effects
				(font
					(size 1.016 1.016)
					(thickness 0.1524)
				)
			)
		)
		(duplicate_pad_numbers_are_jumpers no)
		(fp_line
			(start -0.4826 0)
			(end -0.2032 0)
			(stroke
				(width 0.2032)
				(type default)
			)
			(layer "F.SilkS")
		)
		(fp_line
			(start 0.2032 0)
			(end 0.4826 0)
			(stroke
				(width 0.2032)
				(type default)
			)
			(layer "F.SilkS")
		)
		(fp_rect
			(start -0.5842 1.3335)
			(end 0.5842 -1.3335)
			(stroke
				(width 0)
				(type default)
			)
			(fill no)
			(layer "F.CrtYd")
		)
		(fp_rect
			(start -0.5842 1.3335)
			(end 0.5842 -1.3335)
			(stroke
				(width 0)
				(type default)
			)
			(fill no)
			(layer "F.Fab")
		)
		(pad "1" smd custom
			(at 0 -0.762)
			(size 0.2159 0.2159)
			(layers "F.Cu" "F.Mask" "F.Paste")
			(net "P5V_B_1_VBST")
			(options
				(clearance outline)
				(anchor circle)
			)
			(primitives
				(gr_poly
					(pts
						(arc
							(start -0.3302 -0.4318)
							(mid -0.402042 -0.402042)
							(end -0.4318 -0.3302)
						)
						(arc
							(start -0.4318 0.3302)
							(mid -0.402042 0.402042)
							(end -0.3302 0.4318)
						)
						(arc
							(start 0.3302 0.4318)
							(mid 0.402042 0.402042)
							(end 0.4318 0.3302)
						)
						(arc
							(start 0.4318 -0.3302)
							(mid 0.402042 -0.402042)
							(end 0.3302 -0.4318)
						)
					)
					(width 0)
					(fill yes)
				)
			)
		)
		(pad "2" smd custom
			(at 0 0.762)
			(size 0.2159 0.2159)
			(layers "F.Cu" "F.Mask" "F.Paste")
			(net "P5V_B_1_VBST_RC")
			(options
				(clearance outline)
				(anchor circle)
			)
			(primitives
				(gr_poly
					(pts
						(arc
							(start -0.3302 -0.4318)
							(mid -0.402042 -0.402042)
							(end -0.4318 -0.3302)
						)
						(arc
							(start -0.4318 0.3302)
							(mid -0.402042 0.402042)
							(end -0.3302 0.4318)
						)
						(arc
							(start 0.3302 0.4318)
							(mid 0.402042 0.402042)
							(end 0.4318 0.3302)
						)
						(arc
							(start 0.4318 -0.3302)
							(mid 0.402042 -0.402042)
							(end 0.3302 -0.4318)
						)
					)
					(width 0)
					(fill yes)
				)
			)
		)
	)
	(footprint ""
		(layer "F.Cu")
		(at 143.999966 -180.399944)
		(property "Reference" "LED5"
			(at 0 0 0)
			(layer "F.SilkS")
			(hide yes)
			(effects
				(font
					(size 1.27 1.27)
				)
			)
		)
		(property "Value" "LED-BY-19-GP"
			(at -2.132076 1.414018 0)
			(unlocked yes)
			(layer "F.Fab")
			(hide yes)
			(effects
				(font
					(size 1.016 1.016)
					(thickness 0.1524)
				)
			)
		)
		(property "Device Type" "LED-1615-4PH26"
			(at -2.132076 -0.109982 0)
			(unlocked yes)
			(layer "F.Fab")
			(hide yes)
			(effects
				(font
					(size 1.016 1.016)
					(thickness 0.1524)
				)
			)
		)
		(duplicate_pad_numbers_are_jumpers no)
		(fp_line
			(start -1.2954 0.254)
			(end -1.2954 1.6002)
			(stroke
				(width 0.508)
				(type default)
			)
			(layer "F.SilkS")
		)
		(fp_line
			(start -1.2954 1.6002)
			(end 1.2954 1.6002)
			(stroke
				(width 0.508)
				(type default)
			)
			(layer "F.SilkS")
		)
		(fp_line
			(start -1.1176 -1.4224)
			(end 1.1176 -1.4224)
			(stroke
				(width 0.1524)
				(type default)
			)
			(layer "F.SilkS")
		)
		(fp_line
			(start -1.1176 1.4224)
			(end -1.1176 -1.4224)
			(stroke
				(width 0.1524)
				(type default)
			)
			(layer "F.SilkS")
		)
		(fp_line
			(start 1.1176 -1.4224)
			(end 1.1176 1.4224)
			(stroke
				(width 0.1524)
				(type default)
			)
			(layer "F.SilkS")
		)
		(fp_line
			(start 1.1176 1.4224)
			(end -1.1176 1.4224)
			(stroke
				(width 0.1524)
				(type default)
			)
			(layer "F.SilkS")
		)
		(fp_line
			(start 1.2954 1.6002)
			(end 1.2954 0.254)
			(stroke
				(width 0.508)
				(type default)
			)
			(layer "F.SilkS")
		)
		(fp_rect
			(start -0.7493 0.8001)
			(end 0.7493 -0.8001)
			(stroke
				(width 0)
				(type default)
			)
			(fill no)
			(layer "F.CrtYd")
		)
		(fp_poly
			(pts
				(xy -1.3716 1.6764) (xy -1.3716 -1.6764) (xy 1.3716 -1.6764) (xy 1.3716 0.0635) (xy 0.7493 0.0635)
				(xy 0.7493 -0.8001) (xy -0.7493 -0.8001) (xy -0.7493 0.8001) (xy 0.7493 0.8001) (xy 0.7493 0.0762)
				(xy 1.3716 0.0762) (xy 1.3716 1.6764)
			)
			(stroke
				(width 0)
				(type default)
			)
			(fill no)
			(layer "F.CrtYd")
		)
		(fp_rect
			(start -1.3716 1.6764)
			(end 1.3716 -1.6764)
			(stroke
				(width 0)
				(type default)
			)
			(fill no)
			(layer "F.Fab")
		)
		(pad "1" smd rect
			(at 0.50038 -0.73025)
			(size 0.7112 0.8636)
			(layers "F.Cu" "F.Mask" "F.Paste")
			(net "DRV_ACT_4")
		)
		(pad "2" smd rect
			(at -0.50038 -0.73025)
			(size 0.7112 0.8636)
			(layers "F.Cu" "F.Mask" "F.Paste")
			(net "FLT_HDD4")
		)
		(pad "3" smd rect
			(at 0.50038 0.73025)
			(size 0.7112 0.8636)
			(layers "F.Cu" "F.Mask" "F.Paste")
			(net "DRV_ACT_4_N")
		)
		(pad "4" smd rect
			(at -0.50038 0.73025)
			(size 0.7112 0.8636)
			(layers "F.Cu" "F.Mask" "F.Paste")
			(net "FLT_HDD4_N")
		)
	)
	(footprint ""
		(layer "F.Cu")
		(at 189.009528 -366.124236 180)
		(property "Reference" "U50"
			(at 0 0 180)
			(layer "F.SilkS")
			(hide yes)
			(effects
				(font
					(size 1.27 1.27)
				)
			)
		)
		(property "Value" "SN74LVC1G08DCKR-GP"
			(at -2.3368 -8.6868 180)
			(unlocked yes)
			(layer "F.Fab")
			(hide yes)
			(effects
				(font
					(size 1.016 1.016)
					(thickness 0.1524)
				)
			)
		)
		(property "Device Type" "SC70-5H44"
			(at -2.3114 -10.414 180)
			(unlocked yes)
			(layer "F.Fab")
			(hide yes)
			(effects
				(font
					(size 1.016 1.016)
					(thickness 0.1524)
				)
			)
		)
		(duplicate_pad_numbers_are_jumpers no)
		(fp_line
			(start 1.3843 -1.8034)
			(end 1.3843 -1.1176)
			(stroke
				(width 0.3302)
				(type default)
			)
			(layer "F.SilkS")
		)
		(fp_line
			(start 1.27 1.7018)
			(end -1.27 1.7018)
			(stroke
				(width 0.1524)
				(type default)
			)
			(layer "F.SilkS")
		)
		(fp_line
			(start 1.27 -1.7018)
			(end 1.27 1.7018)
			(stroke
				(width 0.1524)
				(type default)
			)
			(layer "F.SilkS")
		)
		(fp_line
			(start 0.6604 -1.8034)
			(end 1.3843 -1.8034)
			(stroke
				(width 0.3302)
				(type default)
			)
			(layer "F.SilkS")
		)
		(fp_line
			(start -1.27 1.7018)
			(end -1.27 -1.7018)
			(stroke
				(width 0.1524)
				(type default)
			)
			(layer "F.SilkS")
		)
		(fp_line
			(start -1.27 -1.7018)
			(end 1.27 -1.7018)
			(stroke
				(width 0.1524)
				(type default)
			)
			(layer "F.SilkS")
		)
		(fp_rect
			(start -1.524 1.9558)
			(end 1.524 -1.9558)
			(stroke
				(width 0)
				(type default)
			)
			(fill no)
			(layer "F.CrtYd")
		)
		(fp_poly
			(pts
				(xy -1.524 -1.9558) (xy 1.524 -1.9558) (xy 1.524 1.9558) (xy -1.524 1.9558)
			)
			(stroke
				(width 0)
				(type default)
			)
			(fill no)
			(layer "F.Fab")
		)
		(pad "1" smd rect
			(at 0.65024 -0.8255 180)
			(size 0.4064 1.2192)
			(layers "F.Cu" "F.Mask" "F.Paste")
			(net "RDPB_FAN_LED1")
		)
		(pad "2" smd rect
			(at 0 -0.8255 180)
			(size 0.4064 1.2192)
			(layers "F.Cu" "F.Mask" "F.Paste")
			(net "FDPB_FAN_LED1")
		)
		(pad "3" smd rect
			(at -0.65024 -0.8255 180)
			(size 0.4064 1.2192)
			(layers "F.Cu" "F.Mask" "F.Paste")
			(net "GND")
		)
		(pad "4" smd rect
			(at -0.65024 0.8255 180)
			(size 0.4064 1.2192)
			(layers "F.Cu" "F.Mask" "F.Paste")
			(net "FAN_LED1")
		)
		(pad "5" smd rect
			(at 0.65024 0.8255 180)
			(size 0.4064 1.2192)
			(layers "F.Cu" "F.Mask" "F.Paste")
			(net "P3V3_IN")
		)
	)
)
